(kicad_pcb
	(version 20260206)
	(generator "pcbnew")
	(generator_version "10.0")
	(general
		(thickness 1.6)
		(legacy_teardrops no)
	)
	(paper "A4")
	(title_block
		(title "baseboard — 13948-1b.1110WZS1818.brd")
		(comment 1 "Honey Badger (Wiwynn) / footprints 2478-2484 of 2523")
	)
	(layers
		(0 "F.Cu" signal "TOP")
		(4 "In1.Cu" signal "L2GND")
		(6 "In2.Cu" signal "L3")
		(8 "In3.Cu" signal "L4VCC")
		(10 "In4.Cu" signal "L5VCC")
		(12 "In5.Cu" signal "L6")
		(14 "In6.Cu" signal "L7GND")
		(2 "B.Cu" signal "BOTTOM")
		(9 "F.Adhes" user "F.Adhesive")
		(11 "B.Adhes" user "B.Adhesive")
		(13 "F.Paste" user "Package Geometry/Pastemask Top")
		(15 "B.Paste" user "Package Geometry/Pastemask Bottom")
		(5 "F.SilkS" user "Ref Des/Silkscreen Top")
		(7 "B.SilkS" user "Ref Des/Silkscreen Bottom")
		(1 "F.Mask" user "Board Geometry/Soldermask Top")
		(3 "B.Mask" user "Board Geometry/Soldermask Bottom")
		(17 "Dwgs.User" user "User.Drawings")
		(19 "Cmts.User" user "User.Comments")
		(21 "Eco1.User" user "User.Eco1")
		(23 "Eco2.User" user "User.Eco2")
		(25 "Edge.Cuts" user "Board Geometry/Outline")
		(27 "Margin" user)
		(31 "F.CrtYd" user "Package Geometry/Place Bound Top")
		(29 "B.CrtYd" user "Package Geometry/Place Bound Bottom")
		(35 "F.Fab" user "Ref Des/Assembly Top")
		(33 "B.Fab" user "Ref Des/Assembly Bottom")
	)
	(footprint ""
		(layer "B.Cu")
		(at 124.403612 -215.519 90)
		(property "Reference" "SR905"
			(at 0 0 90)
			(layer "B.SilkS")
			(hide yes)
			(effects
				(font
					(size 1.27 1.27)
				)
				(justify mirror)
			)
		)
		(property "Value" "4K7R2F-GP"
			(at -0.064008 -3.993896 90)
			(unlocked yes)
			(layer "B.Fab")
			(hide yes)
			(effects
				(font
					(size 1.016 1.016)
					(thickness 0.1524)
				)
				(justify mirror)
			)
		)
		(property "Device Type" "R402H16"
			(at -0.064008 -5.517896 90)
			(unlocked yes)
			(layer "B.Fab")
			(hide yes)
			(effects
				(font
					(size 1.016 1.016)
					(thickness 0.1524)
				)
				(justify mirror)
			)
		)
		(duplicate_pad_numbers_are_jumpers no)
		(fp_line
			(start 0.508 -0.9398)
			(end 0.508 0.9398)
			(stroke
				(width 0.1524)
				(type default)
			)
			(layer "B.SilkS")
		)
		(fp_line
			(start -0.508 -0.9398)
			(end 0.508 -0.9398)
			(stroke
				(width 0.1524)
				(type default)
			)
			(layer "B.SilkS")
		)
		(fp_rect
			(start 0.508 0.9398)
			(end -0.508 -0.9398)
			(stroke
				(width 0)
				(type default)
			)
			(fill no)
			(layer "B.CrtYd")
		)
		(fp_rect
			(start 0.508 0.9398)
			(end -0.508 -0.9398)
			(stroke
				(width 0)
				(type default)
			)
			(fill no)
			(layer "B.Fab")
		)
		(pad "1" smd custom
			(at 0 -0.4445 270)
			(size 0.1397 0.1397)
			(layers "B.Cu" "B.Mask" "B.Paste")
			(net "REDV_D2_A")
			(options
				(clearance outline)
				(anchor circle)
			)
			(primitives
				(gr_poly
					(pts
						(arc
							(start -0.1778 0.2794)
							(mid -0.249642 0.249642)
							(end -0.2794 0.1778)
						)
						(arc
							(start -0.2794 -0.1778)
							(mid -0.249642 -0.249642)
							(end -0.1778 -0.2794)
						)
						(arc
							(start 0.1778 -0.2794)
							(mid 0.249642 -0.249642)
							(end 0.2794 -0.1778)
						)
						(arc
							(start 0.2794 0.1778)
							(mid 0.249642 0.249642)
							(end 0.1778 0.2794)
						)
					)
					(width 0)
					(fill yes)
				)
			)
		)
		(pad "2" smd custom
			(at 0 0.4445 270)
			(size 0.1397 0.1397)
			(layers "B.Cu" "B.Mask" "B.Paste")
			(net "GND")
			(options
				(clearance outline)
				(anchor circle)
			)
			(primitives
				(gr_poly
					(pts
						(arc
							(start -0.1778 0.2794)
							(mid -0.249642 0.249642)
							(end -0.2794 0.1778)
						)
						(arc
							(start -0.2794 -0.1778)
							(mid -0.249642 -0.249642)
							(end -0.1778 -0.2794)
						)
						(arc
							(start 0.1778 -0.2794)
							(mid 0.249642 -0.249642)
							(end 0.2794 -0.1778)
						)
						(arc
							(start 0.2794 0.1778)
							(mid 0.249642 0.249642)
							(end 0.1778 0.2794)
						)
					)
					(width 0)
					(fill yes)
				)
			)
		)
	)
	(footprint ""
		(layer "B.Cu")
		(at 27.382216 -232.33888)
		(property "Reference" "R504"
			(at 0 0 0)
			(layer "B.SilkS")
			(hide yes)
			(effects
				(font
					(size 1.27 1.27)
				)
				(justify mirror)
			)
		)
		(property "Value" "0R2J-2-GP"
			(at -0.064008 -3.993896 0)
			(unlocked yes)
			(layer "B.Fab")
			(hide yes)
			(effects
				(font
					(size 1.016 1.016)
					(thickness 0.1524)
				)
				(justify mirror)
			)
		)
		(property "Device Type" "R402H16"
			(at -0.064008 -5.517896 0)
			(unlocked yes)
			(layer "B.Fab")
			(hide yes)
			(effects
				(font
					(size 1.016 1.016)
					(thickness 0.1524)
				)
				(justify mirror)
			)
		)
		(duplicate_pad_numbers_are_jumpers no)
		(fp_line
			(start -0.508 -0.9398)
			(end 0.508 -0.9398)
			(stroke
				(width 0.1524)
				(type default)
			)
			(layer "B.SilkS")
		)
		(fp_line
			(start 0.508 -0.9398)
			(end 0.508 0.9398)
			(stroke
				(width 0.1524)
				(type default)
			)
			(layer "B.SilkS")
		)
		(fp_rect
			(start 0.508 0.9398)
			(end -0.508 -0.9398)
			(stroke
				(width 0)
				(type default)
			)
			(fill no)
			(layer "B.CrtYd")
		)
		(fp_rect
			(start 0.508 0.9398)
			(end -0.508 -0.9398)
			(stroke
				(width 0)
				(type default)
			)
			(fill no)
			(layer "B.Fab")
		)
		(pad "1" smd custom
			(at 0 -0.4445 180)
			(size 0.1397 0.1397)
			(layers "B.Cu" "B.Mask" "B.Paste")
			(net "SAS_HDD_PWR2_PCIE")
			(options
				(clearance outline)
				(anchor circle)
			)
			(primitives
				(gr_poly
					(pts
						(arc
							(start -0.1778 0.2794)
							(mid -0.249642 0.249642)
							(end -0.2794 0.1778)
						)
						(arc
							(start -0.2794 -0.1778)
							(mid -0.249642 -0.249642)
							(end -0.1778 -0.2794)
						)
						(arc
							(start 0.1778 -0.2794)
							(mid 0.249642 -0.249642)
							(end 0.2794 -0.1778)
						)
						(arc
							(start 0.2794 0.1778)
							(mid 0.249642 0.249642)
							(end 0.1778 0.2794)
						)
					)
					(width 0)
					(fill yes)
				)
			)
		)
		(pad "2" smd custom
			(at 0 0.4445 180)
			(size 0.1397 0.1397)
			(layers "B.Cu" "B.Mask" "B.Paste")
			(net "SAS_HDD_PWR2")
			(options
				(clearance outline)
				(anchor circle)
			)
			(primitives
				(gr_poly
					(pts
						(arc
							(start -0.1778 0.2794)
							(mid -0.249642 0.249642)
							(end -0.2794 0.1778)
						)
						(arc
							(start -0.2794 -0.1778)
							(mid -0.249642 -0.249642)
							(end -0.1778 -0.2794)
						)
						(arc
							(start 0.1778 -0.2794)
							(mid 0.249642 -0.249642)
							(end 0.2794 -0.1778)
						)
						(arc
							(start 0.2794 0.1778)
							(mid 0.249642 0.249642)
							(end 0.1778 0.2794)
						)
					)
					(width 0)
					(fill yes)
				)
			)
		)
	)
	(footprint ""
		(layer "B.Cu")
		(at 90.68816 -39.37 90)
		(property "Reference" "SC939"
			(at 0 0 90)
			(layer "B.SilkS")
			(hide yes)
			(effects
				(font
					(size 1.27 1.27)
				)
				(justify mirror)
			)
		)
		(property "Value" "SCD1U6D3V1KX-GP"
			(at 2.8321 -1.7399 90)
			(unlocked yes)
			(layer "B.Fab")
			(hide yes)
			(effects
				(font
					(size 1.016 1.016)
					(thickness 0.1524)
				)
				(justify mirror)
			)
		)
		(property "Device Type" "C0201H13"
			(at 2.8321 -3.2639 90)
			(unlocked yes)
			(layer "B.Fab")
			(hide yes)
			(effects
				(font
					(size 1.016 1.016)
					(thickness 0.1524)
				)
				(justify mirror)
			)
		)
		(duplicate_pad_numbers_are_jumpers no)
		(fp_rect
			(start 0.2794 0.6477)
			(end -0.2794 -0.6477)
			(stroke
				(width 0)
				(type default)
			)
			(fill no)
			(layer "B.CrtYd")
		)
		(fp_rect
			(start 0.2794 0.6477)
			(end -0.2794 -0.6477)
			(stroke
				(width 0)
				(type default)
			)
			(fill no)
			(layer "B.Fab")
		)
		(pad "1" smd custom
			(at 0 -0.2794 270)
			(size 0.0762 0.0762)
			(layers "B.Cu" "B.Mask" "B.Paste")
			(net "SAS0_VDDH")
			(options
				(clearance outline)
				(anchor circle)
			)
			(primitives
				(gr_poly
					(pts
						(arc
							(start 0.1524 0.127)
							(mid 0.137521 0.162921)
							(end 0.1016 0.1778)
						)
						(arc
							(start -0.1016 0.1778)
							(mid -0.137521 0.162921)
							(end -0.1524 0.127)
						)
						(arc
							(start -0.1524 -0.127)
							(mid -0.137521 -0.162921)
							(end -0.1016 -0.1778)
						)
						(arc
							(start 0.1016 -0.1778)
							(mid 0.137521 -0.162921)
							(end 0.1524 -0.127)
						)
					)
					(width 0)
					(fill yes)
				)
			)
		)
		(pad "2" smd custom
			(at 0 0.2794 270)
			(size 0.0762 0.0762)
			(layers "B.Cu" "B.Mask" "B.Paste")
			(net "GND")
			(options
				(clearance outline)
				(anchor circle)
			)
			(primitives
				(gr_poly
					(pts
						(arc
							(start 0.1524 0.127)
							(mid 0.137521 0.162921)
							(end 0.1016 0.1778)
						)
						(arc
							(start -0.1016 0.1778)
							(mid -0.137521 0.162921)
							(end -0.1524 0.127)
						)
						(arc
							(start -0.1524 -0.127)
							(mid -0.137521 -0.162921)
							(end -0.1016 -0.1778)
						)
						(arc
							(start 0.1016 -0.1778)
							(mid 0.137521 -0.162921)
							(end 0.1524 -0.127)
						)
					)
					(width 0)
					(fill yes)
				)
			)
		)
	)
	(footprint ""
		(layer "B.Cu")
		(at 122.18797 -103.378 180)
		(property "Reference" "SC1180"
			(at 0 0 0)
			(layer "B.SilkS")
			(hide yes)
			(effects
				(font
					(size 1.27 1.27)
				)
				(justify mirror)
			)
		)
		(property "Value" "SCD1U6D3V1KX-GP"
			(at 2.8321 -1.7399 180)
			(unlocked yes)
			(layer "B.Fab")
			(hide yes)
			(effects
				(font
					(size 1.016 1.016)
					(thickness 0.1524)
				)
				(justify mirror)
			)
		)
		(property "Device Type" "C0201H13"
			(at 2.8321 -3.2639 180)
			(unlocked yes)
			(layer "B.Fab")
			(hide yes)
			(effects
				(font
					(size 1.016 1.016)
					(thickness 0.1524)
				)
				(justify mirror)
			)
		)
		(duplicate_pad_numbers_are_jumpers no)
		(fp_rect
			(start 0.2794 0.6477)
			(end -0.2794 -0.6477)
			(stroke
				(width 0)
				(type default)
			)
			(fill no)
			(layer "B.CrtYd")
		)
		(fp_rect
			(start 0.2794 0.6477)
			(end -0.2794 -0.6477)
			(stroke
				(width 0)
				(type default)
			)
			(fill no)
			(layer "B.Fab")
		)
		(pad "1" smd custom
			(at 0 -0.2794)
			(size 0.0762 0.0762)
			(layers "B.Cu" "B.Mask" "B.Paste")
			(net "GB_VDDA")
			(options
				(clearance outline)
				(anchor circle)
			)
			(primitives
				(gr_poly
					(pts
						(arc
							(start 0.1524 0.127)
							(mid 0.137521 0.162921)
							(end 0.1016 0.1778)
						)
						(arc
							(start -0.1016 0.1778)
							(mid -0.137521 0.162921)
							(end -0.1524 0.127)
						)
						(arc
							(start -0.1524 -0.127)
							(mid -0.137521 -0.162921)
							(end -0.1016 -0.1778)
						)
						(arc
							(start 0.1016 -0.1778)
							(mid 0.137521 -0.162921)
							(end 0.1524 -0.127)
						)
					)
					(width 0)
					(fill yes)
				)
			)
		)
		(pad "2" smd custom
			(at 0 0.2794)
			(size 0.0762 0.0762)
			(layers "B.Cu" "B.Mask" "B.Paste")
			(net "GND")
			(options
				(clearance outline)
				(anchor circle)
			)
			(primitives
				(gr_poly
					(pts
						(arc
							(start 0.1524 0.127)
							(mid 0.137521 0.162921)
							(end 0.1016 0.1778)
						)
						(arc
							(start -0.1016 0.1778)
							(mid -0.137521 0.162921)
							(end -0.1524 0.127)
						)
						(arc
							(start -0.1524 -0.127)
							(mid -0.137521 -0.162921)
							(end -0.1016 -0.1778)
						)
						(arc
							(start 0.1016 -0.1778)
							(mid 0.137521 -0.162921)
							(end 0.1524 -0.127)
						)
					)
					(width 0)
					(fill yes)
				)
			)
		)
	)
	(footprint ""
		(layer "B.Cu")
		(at 114.56797 -96.52 180)
		(property "Reference" "SC1216"
			(at 0 0 0)
			(layer "B.SilkS")
			(hide yes)
			(effects
				(font
					(size 1.27 1.27)
				)
				(justify mirror)
			)
		)
		(property "Value" "SC1KP50V2KX-1GP"
			(at -1.1811 -2.7051 180)
			(unlocked yes)
			(layer "B.Fab")
			(hide yes)
			(effects
				(font
					(size 1.016 1.016)
					(thickness 0.1524)
				)
				(justify mirror)
			)
		)
		(property "Device Type" "C402H22"
			(at -1.1811 -4.2291 180)
			(unlocked yes)
			(layer "B.Fab")
			(hide yes)
			(effects
				(font
					(size 1.016 1.016)
					(thickness 0.1524)
				)
				(justify mirror)
			)
		)
		(duplicate_pad_numbers_are_jumpers no)
		(fp_rect
			(start 0.4318 0.9525)
			(end -0.4318 -0.9525)
			(stroke
				(width 0)
				(type default)
			)
			(fill no)
			(layer "B.CrtYd")
		)
		(fp_rect
			(start 0.4318 0.9525)
			(end -0.4318 -0.9525)
			(stroke
				(width 0)
				(type default)
			)
			(fill no)
			(layer "B.Fab")
		)
		(pad "1" smd custom
			(at 0 -0.4445)
			(size 0.1524 0.1524)
			(layers "B.Cu" "B.Mask" "B.Paste")
			(net "P0V9_E")
			(options
				(clearance outline)
				(anchor circle)
			)
			(primitives
				(gr_poly
					(pts
						(arc
							(start 0.3048 0.2032)
							(mid 0.275042 0.275042)
							(end 0.2032 0.3048)
						)
						(arc
							(start -0.2032 0.3048)
							(mid -0.275042 0.275042)
							(end -0.3048 0.2032)
						)
						(arc
							(start -0.3048 -0.2032)
							(mid -0.275042 -0.275042)
							(end -0.2032 -0.3048)
						)
						(arc
							(start 0.2032 -0.3048)
							(mid 0.275042 -0.275042)
							(end 0.3048 -0.2032)
						)
					)
					(width 0)
					(fill yes)
				)
			)
		)
		(pad "2" smd custom
			(at 0 0.4445)
			(size 0.1524 0.1524)
			(layers "B.Cu" "B.Mask" "B.Paste")
			(net "GND")
			(options
				(clearance outline)
				(anchor circle)
			)
			(primitives
				(gr_poly
					(pts
						(arc
							(start 0.3048 0.2032)
							(mid 0.275042 0.275042)
							(end 0.2032 0.3048)
						)
						(arc
							(start -0.2032 0.3048)
							(mid -0.275042 0.275042)
							(end -0.3048 0.2032)
						)
						(arc
							(start -0.3048 -0.2032)
							(mid -0.275042 -0.275042)
							(end -0.2032 -0.3048)
						)
						(arc
							(start 0.2032 -0.3048)
							(mid 0.275042 -0.275042)
							(end 0.3048 -0.2032)
						)
					)
					(width 0)
					(fill yes)
				)
			)
		)
	)
	(footprint ""
		(layer "B.Cu")
		(at 13.34008 -231.822752)
		(property "Reference" "R514"
			(at 0 0 0)
			(layer "B.SilkS")
			(hide yes)
			(effects
				(font
					(size 1.27 1.27)
				)
				(justify mirror)
			)
		)
		(property "Value" "0R2J-2-GP"
			(at -0.064008 -3.993896 0)
			(unlocked yes)
			(layer "B.Fab")
			(hide yes)
			(effects
				(font
					(size 1.016 1.016)
					(thickness 0.1524)
				)
				(justify mirror)
			)
		)
		(property "Device Type" "R402H16"
			(at -0.064008 -5.517896 0)
			(unlocked yes)
			(layer "B.Fab")
			(hide yes)
			(effects
				(font
					(size 1.016 1.016)
					(thickness 0.1524)
				)
				(justify mirror)
			)
		)
		(duplicate_pad_numbers_are_jumpers no)
		(fp_line
			(start -0.508 -0.9398)
			(end 0.508 -0.9398)
			(stroke
				(width 0.1524)
				(type default)
			)
			(layer "B.SilkS")
		)
		(fp_line
			(start 0.508 -0.9398)
			(end 0.508 0.9398)
			(stroke
				(width 0.1524)
				(type default)
			)
			(layer "B.SilkS")
		)
		(fp_rect
			(start 0.508 0.9398)
			(end -0.508 -0.9398)
			(stroke
				(width 0)
				(type default)
			)
			(fill no)
			(layer "B.CrtYd")
		)
		(fp_rect
			(start 0.508 0.9398)
			(end -0.508 -0.9398)
			(stroke
				(width 0)
				(type default)
			)
			(fill no)
			(layer "B.Fab")
		)
		(pad "1" smd custom
			(at 0 -0.4445 180)
			(size 0.1397 0.1397)
			(layers "B.Cu" "B.Mask" "B.Paste")
			(net "SAS_HDD_PWR12_PCIE")
			(options
				(clearance outline)
				(anchor circle)
			)
			(primitives
				(gr_poly
					(pts
						(arc
							(start -0.1778 0.2794)
							(mid -0.249642 0.249642)
							(end -0.2794 0.1778)
						)
						(arc
							(start -0.2794 -0.1778)
							(mid -0.249642 -0.249642)
							(end -0.1778 -0.2794)
						)
						(arc
							(start 0.1778 -0.2794)
							(mid 0.249642 -0.249642)
							(end 0.2794 -0.1778)
						)
						(arc
							(start 0.2794 0.1778)
							(mid 0.249642 0.249642)
							(end 0.1778 0.2794)
						)
					)
					(width 0)
					(fill yes)
				)
			)
		)
		(pad "2" smd custom
			(at 0 0.4445 180)
			(size 0.1397 0.1397)
			(layers "B.Cu" "B.Mask" "B.Paste")
			(net "SAS_HDD_PWR12")
			(options
				(clearance outline)
				(anchor circle)
			)
			(primitives
				(gr_poly
					(pts
						(arc
							(start -0.1778 0.2794)
							(mid -0.249642 0.249642)
							(end -0.2794 0.1778)
						)
						(arc
							(start -0.2794 -0.1778)
							(mid -0.249642 -0.249642)
							(end -0.1778 -0.2794)
						)
						(arc
							(start 0.1778 -0.2794)
							(mid 0.249642 -0.249642)
							(end 0.2794 -0.1778)
						)
						(arc
							(start 0.2794 0.1778)
							(mid 0.249642 0.249642)
							(end 0.1778 0.2794)
						)
					)
					(width 0)
					(fill yes)
				)
			)
		)
	)
	(footprint ""
		(layer "B.Cu")
		(at 180.275992 -29.718 90)
		(property "Reference" "BC1"
			(at 0 0 90)
			(layer "B.SilkS")
			(hide yes)
			(effects
				(font
					(size 1.27 1.27)
				)
				(justify mirror)
			)
		)
		(property "Value" "SC2D2U10V3KX-1GP"
			(at 0 -2.8194 90)
			(unlocked yes)
			(layer "B.Fab")
			(hide yes)
			(effects
				(font
					(size 1.016 1.016)
					(thickness 0.1524)
				)
				(justify mirror)
			)
		)
		(property "Device Type" "C603H36"
			(at 0 -4.3434 90)
			(unlocked yes)
			(layer "B.Fab")
			(hide yes)
			(effects
				(font
					(size 1.016 1.016)
					(thickness 0.1524)
				)
				(justify mirror)
			)
		)
		(duplicate_pad_numbers_are_jumpers no)
		(fp_line
			(start -0.508 0)
			(end 0.508 0)
			(stroke
				(width 0.2032)
				(type default)
			)
			(layer "B.SilkS")
		)
		(fp_rect
			(start 0.5842 1.3335)
			(end -0.5842 -1.3335)
			(stroke
				(width 0)
				(type default)
			)
			(fill no)
			(layer "B.CrtYd")
		)
		(fp_rect
			(start 0.5842 1.3335)
			(end -0.5842 -1.3335)
			(stroke
				(width 0)
				(type default)
			)
			(fill no)
			(layer "B.Fab")
		)
		(pad "1" smd custom
			(at 0 -0.762 270)
			(size 0.2159 0.2159)
			(layers "B.Cu" "B.Mask" "B.Paste")
			(net "PHY_AVDD")
			(options
				(clearance outline)
				(anchor circle)
			)
			(primitives
				(gr_poly
					(pts
						(arc
							(start -0.3302 0.4318)
							(mid -0.402042 0.402042)
							(end -0.4318 0.3302)
						)
						(arc
							(start -0.4318 -0.3302)
							(mid -0.402042 -0.402042)
							(end -0.3302 -0.4318)
						)
						(arc
							(start 0.3302 -0.4318)
							(mid 0.402042 -0.402042)
							(end 0.4318 -0.3302)
						)
						(arc
							(start 0.4318 0.3302)
							(mid 0.402042 0.402042)
							(end 0.3302 0.4318)
						)
					)
					(width 0)
					(fill yes)
				)
			)
		)
		(pad "2" smd custom
			(at 0 0.762 270)
			(size 0.2159 0.2159)
			(layers "B.Cu" "B.Mask" "B.Paste")
			(net "GND")
			(options
				(clearance outline)
				(anchor circle)
			)
			(primitives
				(gr_poly
					(pts
						(arc
							(start -0.3302 0.4318)
							(mid -0.402042 0.402042)
							(end -0.4318 0.3302)
						)
						(arc
							(start -0.4318 -0.3302)
							(mid -0.402042 -0.402042)
							(end -0.3302 -0.4318)
						)
						(arc
							(start 0.3302 -0.4318)
							(mid 0.402042 -0.402042)
							(end 0.4318 -0.3302)
						)
						(arc
							(start 0.4318 0.3302)
							(mid 0.402042 0.402042)
							(end 0.3302 0.4318)
						)
					)
					(width 0)
					(fill yes)
				)
			)
		)
	)
)
